# SCM (Grand Teton) — schematic netlist excerpt (pin names and nets, part order shuffled) for the footprints in the layout excerpt that follows; sources: Cadence DE-HDL packaged netlist, KiCad conversion of 12092022_DA0F0TMDCD0_F0T_Management_Board_D_brd_V3_OCP.brd

R244  Q_RES  1.8K 1% CHIP  pkg 0402LF  page 27 : A = P3V3_AUX ; B = SMB_BMC_MM1_SCL
PR500  Q_RES  10K 1% CHIP  pkg 0402LF  page 56 : A = P3V3_AUX ; B = PWRGD_P1V0_AUX_R

(kicad_pcb
	(version 20260206)
	(generator "pcbnew")
	(generator_version "10.0")
	(general
		(thickness 1.6)
		(legacy_teardrops no)
	)
	(paper "A4")
	(title_block
		(title "12092022_DA0F0TMDCD0_F0T_Management_Board_D_brd_V3_OCP.brd")
		(comment 1 "Grand Teton / footprints 278-279 of 1440")
	)
	(layers
		(0 "F.Cu" signal "TOP")
		(4 "In1.Cu" signal "GND")
		(6 "In2.Cu" signal "IN1")
		(8 "In3.Cu" signal "GND1")
		(10 "In4.Cu" signal "IN2")
		(12 "In5.Cu" signal "VCC")
		(14 "In6.Cu" signal "VCC1")
		(16 "In7.Cu" signal "IN3")
		(18 "In8.Cu" signal "GND2")
		(20 "In9.Cu" signal "IN4")
		(22 "In10.Cu" signal "GND3")
		(2 "B.Cu" signal "BOTTOM")
		(9 "F.Adhes" user "F.Adhesive")
		(11 "B.Adhes" user "B.Adhesive")
		(13 "F.Paste" user "Package Geometry/Pastemask Top")
		(15 "B.Paste" user "Package Geometry/Pastemask Bottom")
		(5 "F.SilkS" user "Ref Des/Silkscreen Top")
		(7 "B.SilkS" user "Ref Des/Silkscreen Bottom")
		(1 "F.Mask" user "Board Geometry/Soldermask Top")
		(3 "B.Mask" user "Board Geometry/Soldermask Bottom")
		(17 "Dwgs.User" user "User.Drawings")
		(19 "Cmts.User" user "User.Comments")
		(21 "Eco1.User" user "User.Eco1")
		(23 "Eco2.User" user "User.Eco2")
		(25 "Edge.Cuts" user "Board Geometry/Outline")
		(27 "Margin" user)
		(31 "F.CrtYd" user "Package Geometry/Place Bound Top")
		(29 "B.CrtYd" user "Package Geometry/Place Bound Bottom")
		(35 "F.Fab" user "Ref Des/Assembly Top")
		(33 "B.Fab" user "Ref Des/Assembly Bottom")
	)
	(footprint ""
		(layer "F.Cu")
		(at 45.259244 -30.791404 90)
		(property "Reference" "R244"
			(at 0 0 90)
			(layer "F.SilkS")
			(hide yes)
			(effects
				(font
					(size 1.27 1.27)
				)
			)
		)
		(property "Value" ""
			(at 0 0 90)
			(layer "F.Fab")
			(effects
				(font
					(size 1.27 1.27)
				)
			)
		)
		(duplicate_pad_numbers_are_jumpers no)
		(fp_line
			(start 0.7874 -0.4064)
			(end 0.7874 0.4064)
			(stroke
				(width 0.1524)
				(type default)
			)
			(layer "F.SilkS")
		)
		(fp_line
			(start -0.7874 -0.4064)
			(end 0.7874 -0.4064)
			(stroke
				(width 0.1524)
				(type default)
			)
			(layer "F.SilkS")
		)
		(fp_line
			(start 0.7874 0.4064)
			(end -0.7874 0.4064)
			(stroke
				(width 0.1524)
				(type default)
			)
			(layer "F.SilkS")
		)
		(fp_line
			(start -0.7874 0.4064)
			(end -0.7874 -0.4064)
			(stroke
				(width 0.1524)
				(type default)
			)
			(layer "F.SilkS")
		)
		(fp_line
			(start -0.12065 -0.305054)
			(end -0.12065 -0.2794)
			(stroke
				(width 0.1)
				(type default)
			)
			(layer "F.Fab")
		)
		(fp_line
			(start -0.67945 -0.305054)
			(end -0.12065 -0.305054)
			(stroke
				(width 0.1)
				(type default)
			)
			(layer "F.Fab")
		)
		(fp_line
			(start 0.67945 -0.3048)
			(end 0.67945 0.3048)
			(stroke
				(width 0.1)
				(type default)
			)
			(layer "F.Fab")
		)
		(fp_line
			(start 0.12065 -0.3048)
			(end 0.67945 -0.3048)
			(stroke
				(width 0.1)
				(type default)
			)
			(layer "F.Fab")
		)
		(fp_line
			(start 0.12065 -0.2794)
			(end 0.12065 -0.3048)
			(stroke
				(width 0.1)
				(type default)
			)
			(layer "F.Fab")
		)
		(fp_line
			(start -0.12065 -0.2794)
			(end 0.12065 -0.2794)
			(stroke
				(width 0.1)
				(type default)
			)
			(layer "F.Fab")
		)
		(fp_line
			(start 0.120396 0.2794)
			(end -0.12065 0.2794)
			(stroke
				(width 0.1)
				(type default)
			)
			(layer "F.Fab")
		)
		(fp_line
			(start -0.12065 0.2794)
			(end -0.12065 0.3048)
			(stroke
				(width 0.1)
				(type default)
			)
			(layer "F.Fab")
		)
		(fp_line
			(start 0.67945 0.3048)
			(end 0.120396 0.3048)
			(stroke
				(width 0.1)
				(type default)
			)
			(layer "F.Fab")
		)
		(fp_line
			(start 0.120396 0.3048)
			(end 0.120396 0.2794)
			(stroke
				(width 0.1)
				(type default)
			)
			(layer "F.Fab")
		)
		(fp_line
			(start -0.12065 0.3048)
			(end -0.67945 0.3048)
			(stroke
				(width 0.1)
				(type default)
			)
			(layer "F.Fab")
		)
		(fp_line
			(start -0.67945 0.3048)
			(end -0.67945 -0.305054)
			(stroke
				(width 0.1)
				(type default)
			)
			(layer "F.Fab")
		)
		(pad "1" smd circle
			(at -0.40005 0 90)
			(size 0 0)
			(layers "F.Cu" "F.Mask" "F.Paste")
			(net "P3V3_AUX")
		)
		(pad "2" smd circle
			(at 0.40005 0 90)
			(size 0 0)
			(layers "F.Cu" "F.Mask" "F.Paste")
			(net "SMB_BMC_MM1_SCL")
		)
	)
	(footprint ""
		(layer "F.Cu")
		(at 23.47087 -33.904174 -90)
		(property "Reference" "PR500"
			(at 0 0 270)
			(layer "F.SilkS")
			(hide yes)
			(effects
				(font
					(size 1.27 1.27)
				)
			)
		)
		(property "Value" ""
			(at 0 0 270)
			(layer "F.Fab")
			(effects
				(font
					(size 1.27 1.27)
				)
			)
		)
		(duplicate_pad_numbers_are_jumpers no)
		(fp_line
			(start -0.7874 0.4064)
			(end -0.7874 -0.4064)
			(stroke
				(width 0.1524)
				(type default)
			)
			(layer "F.SilkS")
		)
		(fp_line
			(start 0.7874 0.4064)
			(end -0.7874 0.4064)
			(stroke
				(width 0.1524)
				(type default)
			)
			(layer "F.SilkS")
		)
		(fp_line
			(start -0.7874 -0.4064)
			(end 0.7874 -0.4064)
			(stroke
				(width 0.1524)
				(type default)
			)
			(layer "F.SilkS")
		)
		(fp_line
			(start 0.7874 -0.4064)
			(end 0.7874 0.4064)
			(stroke
				(width 0.1524)
				(type default)
			)
			(layer "F.SilkS")
		)
		(fp_line
			(start -0.67945 0.3048)
			(end -0.67945 -0.305054)
			(stroke
				(width 0.1)
				(type default)
			)
			(layer "F.Fab")
		)
		(fp_line
			(start -0.12065 0.3048)
			(end -0.67945 0.3048)
			(stroke
				(width 0.1)
				(type default)
			)
			(layer "F.Fab")
		)
		(fp_line
			(start 0.120396 0.3048)
			(end 0.120396 0.2794)
			(stroke
				(width 0.1)
				(type default)
			)
			(layer "F.Fab")
		)
		(fp_line
			(start 0.67945 0.3048)
			(end 0.120396 0.3048)
			(stroke
				(width 0.1)
				(type default)
			)
			(layer "F.Fab")
		)
		(fp_line
			(start -0.12065 0.2794)
			(end -0.12065 0.3048)
			(stroke
				(width 0.1)
				(type default)
			)
			(layer "F.Fab")
		)
		(fp_line
			(start 0.120396 0.2794)
			(end -0.12065 0.2794)
			(stroke
				(width 0.1)
				(type default)
			)
			(layer "F.Fab")
		)
		(fp_line
			(start -0.12065 -0.2794)
			(end 0.12065 -0.2794)
			(stroke
				(width 0.1)
				(type default)
			)
			(layer "F.Fab")
		)
		(fp_line
			(start 0.12065 -0.2794)
			(end 0.12065 -0.3048)
			(stroke
				(width 0.1)
				(type default)
			)
			(layer "F.Fab")
		)
		(fp_line
			(start 0.12065 -0.3048)
			(end 0.67945 -0.3048)
			(stroke
				(width 0.1)
				(type default)
			)
			(layer "F.Fab")
		)
		(fp_line
			(start 0.67945 -0.3048)
			(end 0.67945 0.3048)
			(stroke
				(width 0.1)
				(type default)
			)
			(layer "F.Fab")
		)
		(fp_line
			(start -0.67945 -0.305054)
			(end -0.12065 -0.305054)
			(stroke
				(width 0.1)
				(type default)
			)
			(layer "F.Fab")
		)
		(fp_line
			(start -0.12065 -0.305054)
			(end -0.12065 -0.2794)
			(stroke
				(width 0.1)
				(type default)
			)
			(layer "F.Fab")
		)
		(pad "1" smd circle
			(at -0.40005 0 270)
			(size 0 0)
			(layers "F.Cu" "F.Mask" "F.Paste")
			(net "P3V3_AUX")
		)
		(pad "2" smd circle
			(at 0.40005 0 270)
			(size 0 0)
			(layers "F.Cu" "F.Mask" "F.Paste")
			(net "PWRGD_P1V0_AUX_R")
		)
	)
)
